# T6G (Grand Teton) — schematic netlist excerpt (pin names and nets, part order shuffled) for the footprints in the layout excerpt that follows; sources: Cadence DE-HDL packaged netlist, KiCad conversion of 04192023_DAF0TMB3IC0_F0TG_MB_C_brd_V02_OCP.brd

C2374  Q_CAP  22UF 4V 20% X6S  pkg C0402  page 73 : A = PVDDCR_CPU1_P1 ; B = GND
C474  Q_CAP  100UF 4V 20% X6S  pkg C0805  page 356 : A = P0V9_CPU1_RT_2D ; B = GND
PR355  Q_RES  0 5% CHIP  pkg 0402LF  page 196 : A = PVDDCR_CPU0_P0_VOS5 ; B = PVDDCR_CPU0_P0

(kicad_pcb
	(version 20260206)
	(generator "pcbnew")
	(generator_version "10.0")
	(general
		(thickness 1.6)
		(legacy_teardrops no)
	)
	(paper "A4")
	(title_block
		(title "04192023_DAF0TMB3IC0_F0TG_MB_C_brd_V02_OCP.brd")
		(comment 1 "Grand Teton / footprints 6905-6907 of 8354")
	)
	(layers
		(0 "F.Cu" signal "TOP")
		(4 "In1.Cu" signal "GND")
		(6 "In2.Cu" signal "IN1")
		(8 "In3.Cu" signal "GND1")
		(10 "In4.Cu" signal "IN2")
		(12 "In5.Cu" signal "GND2")
		(14 "In6.Cu" signal "IN3")
		(16 "In7.Cu" signal "GND3")
		(18 "In8.Cu" signal "VCC")
		(20 "In9.Cu" signal "VCC1")
		(22 "In10.Cu" signal "GND4")
		(24 "In11.Cu" signal "IN4")
		(26 "In12.Cu" signal "GND5")
		(28 "In13.Cu" signal "IN5")
		(30 "In14.Cu" signal "GND6")
		(32 "In15.Cu" signal "IN6")
		(34 "In16.Cu" signal "GND7")
		(2 "B.Cu" signal "BOTTOM")
		(9 "F.Adhes" user "F.Adhesive")
		(11 "B.Adhes" user "B.Adhesive")
		(13 "F.Paste" user "Package Geometry/Pastemask Top")
		(15 "B.Paste" user "Package Geometry/Pastemask Bottom")
		(5 "F.SilkS" user "Ref Des/Silkscreen Top")
		(7 "B.SilkS" user "Ref Des/Silkscreen Bottom")
		(1 "F.Mask" user "Board Geometry/Soldermask Top")
		(3 "B.Mask" user "Board Geometry/Soldermask Bottom")
		(17 "Dwgs.User" user "User.Drawings")
		(19 "Cmts.User" user "User.Comments")
		(21 "Eco1.User" user "User.Eco1")
		(23 "Eco2.User" user "User.Eco2")
		(25 "Edge.Cuts" user "Board Geometry/Outline")
		(27 "Margin" user)
		(31 "F.CrtYd" user "Package Geometry/Place Bound Top")
		(29 "B.CrtYd" user "Package Geometry/Place Bound Bottom")
		(35 "F.Fab" user "Ref Des/Assembly Top")
		(33 "B.Fab" user "Ref Des/Assembly Bottom")
	)
	(footprint ""
		(layer "B.Cu")
		(at 107.863386 -268.418564)
		(property "Reference" "C2374"
			(at 0 0 0)
			(layer "B.SilkS")
			(hide yes)
			(effects
				(font
					(size 1.27 1.27)
				)
				(justify mirror)
			)
		)
		(property "Value" ""
			(at 0 0 0)
			(layer "B.Fab")
			(effects
				(font
					(size 1.27 1.27)
				)
				(justify mirror)
			)
		)
		(duplicate_pad_numbers_are_jumpers no)
		(fp_line
			(start -0.7874 -0.4064)
			(end -0.7874 0.4064)
			(stroke
				(width 0.1524)
				(type default)
			)
			(layer "B.SilkS")
		)
		(fp_line
			(start -0.7874 0.4064)
			(end 0.7874 0.4064)
			(stroke
				(width 0.1524)
				(type default)
			)
			(layer "B.SilkS")
		)
		(fp_line
			(start 0.7874 -0.4064)
			(end -0.7874 -0.4064)
			(stroke
				(width 0.1524)
				(type default)
			)
			(layer "B.SilkS")
		)
		(fp_line
			(start 0.7874 0.4064)
			(end 0.7874 -0.4064)
			(stroke
				(width 0.1524)
				(type default)
			)
			(layer "B.SilkS")
		)
		(fp_line
			(start -0.67945 -0.3048)
			(end -0.67945 0.3048)
			(stroke
				(width 0.1)
				(type default)
			)
			(layer "B.Fab")
		)
		(fp_line
			(start -0.67945 0.3048)
			(end -0.120396 0.3048)
			(stroke
				(width 0.1)
				(type default)
			)
			(layer "B.Fab")
		)
		(fp_line
			(start -0.12065 -0.3048)
			(end -0.67945 -0.3048)
			(stroke
				(width 0.1)
				(type default)
			)
			(layer "B.Fab")
		)
		(fp_line
			(start -0.12065 -0.2794)
			(end -0.12065 -0.3048)
			(stroke
				(width 0.1)
				(type default)
			)
			(layer "B.Fab")
		)
		(fp_line
			(start -0.120396 0.2794)
			(end 0.12065 0.2794)
			(stroke
				(width 0.1)
				(type default)
			)
			(layer "B.Fab")
		)
		(fp_line
			(start -0.120396 0.3048)
			(end -0.120396 0.2794)
			(stroke
				(width 0.1)
				(type default)
			)
			(layer "B.Fab")
		)
		(fp_line
			(start 0.12065 -0.305054)
			(end 0.12065 -0.2794)
			(stroke
				(width 0.1)
				(type default)
			)
			(layer "B.Fab")
		)
		(fp_line
			(start 0.12065 -0.2794)
			(end -0.12065 -0.2794)
			(stroke
				(width 0.1)
				(type default)
			)
			(layer "B.Fab")
		)
		(fp_line
			(start 0.12065 0.2794)
			(end 0.12065 0.3048)
			(stroke
				(width 0.1)
				(type default)
			)
			(layer "B.Fab")
		)
		(fp_line
			(start 0.12065 0.3048)
			(end 0.67945 0.3048)
			(stroke
				(width 0.1)
				(type default)
			)
			(layer "B.Fab")
		)
		(fp_line
			(start 0.67945 -0.305054)
			(end 0.12065 -0.305054)
			(stroke
				(width 0.1)
				(type default)
			)
			(layer "B.Fab")
		)
		(fp_line
			(start 0.67945 0.3048)
			(end 0.67945 -0.305054)
			(stroke
				(width 0.1)
				(type default)
			)
			(layer "B.Fab")
		)
		(pad "1" smd circle
			(at 0.40005 0 180)
			(size 0 0)
			(layers "B.Cu" "B.Mask" "B.Paste")
			(net "PVDDCR_CPU1_P1")
		)
		(pad "2" smd circle
			(at -0.40005 0 180)
			(size 0 0)
			(layers "B.Cu" "B.Mask" "B.Paste")
			(net "GND")
		)
	)
	(footprint ""
		(layer "B.Cu")
		(at 107.034838 -389.673084 90)
		(property "Reference" "C474"
			(at 0 0 90)
			(layer "B.SilkS")
			(hide yes)
			(effects
				(font
					(size 1.27 1.27)
				)
				(justify mirror)
			)
		)
		(property "Value" ""
			(at 0 0 90)
			(layer "B.Fab")
			(effects
				(font
					(size 1.27 1.27)
				)
				(justify mirror)
			)
		)
		(duplicate_pad_numbers_are_jumpers no)
		(fp_line
			(start 1.524 -0.762)
			(end -1.524 -0.762)
			(stroke
				(width 0.1524)
				(type default)
			)
			(layer "B.SilkS")
		)
		(fp_line
			(start -1.524 -0.762)
			(end -1.524 0.762)
			(stroke
				(width 0.1524)
				(type default)
			)
			(layer "B.SilkS")
		)
		(fp_line
			(start 1.524 0.762)
			(end 1.524 -0.762)
			(stroke
				(width 0.1524)
				(type default)
			)
			(layer "B.SilkS")
		)
		(fp_line
			(start -1.524 0.762)
			(end 1.524 0.762)
			(stroke
				(width 0.1524)
				(type default)
			)
			(layer "B.SilkS")
		)
		(fp_line
			(start 1.1049 -0.724916)
			(end 1.1049 0.724916)
			(stroke
				(width 0.1)
				(type default)
			)
			(layer "B.Fab")
		)
		(fp_line
			(start -1.1049 -0.724916)
			(end 1.1049 -0.724916)
			(stroke
				(width 0.1)
				(type default)
			)
			(layer "B.Fab")
		)
		(fp_line
			(start 1.1049 0.724916)
			(end -1.1049 0.724916)
			(stroke
				(width 0.1)
				(type default)
			)
			(layer "B.Fab")
		)
		(fp_line
			(start -1.1049 0.724916)
			(end -1.1049 -0.724916)
			(stroke
				(width 0.1)
				(type default)
			)
			(layer "B.Fab")
		)
		(pad "1" smd rect
			(at 0.889 0 90)
			(size 1.016 1.27)
			(layers "B.Cu" "B.Mask" "B.Paste")
			(net "P0V9_CPU1_RT_2D")
		)
		(pad "2" smd rect
			(at -0.889 0 90)
			(size 1.016 1.27)
			(layers "B.Cu" "B.Mask" "B.Paste")
			(net "GND")
		)
	)
	(footprint ""
		(layer "B.Cu")
		(at 359.694988 -166.830756 90)
		(property "Reference" "PR355"
			(at 0 0 90)
			(layer "B.SilkS")
			(hide yes)
			(effects
				(font
					(size 1.27 1.27)
				)
				(justify mirror)
			)
		)
		(property "Value" ""
			(at 0 0 90)
			(layer "B.Fab")
			(effects
				(font
					(size 1.27 1.27)
				)
				(justify mirror)
			)
		)
		(duplicate_pad_numbers_are_jumpers no)
		(fp_line
			(start 0.7874 -0.4064)
			(end -0.7874 -0.4064)
			(stroke
				(width 0.1524)
				(type default)
			)
			(layer "B.SilkS")
		)
		(fp_line
			(start -0.7874 -0.4064)
			(end -0.7874 0.4064)
			(stroke
				(width 0.1524)
				(type default)
			)
			(layer "B.SilkS")
		)
		(fp_line
			(start 0.7874 0.4064)
			(end 0.7874 -0.4064)
			(stroke
				(width 0.1524)
				(type default)
			)
			(layer "B.SilkS")
		)
		(fp_line
			(start -0.7874 0.4064)
			(end 0.7874 0.4064)
			(stroke
				(width 0.1524)
				(type default)
			)
			(layer "B.SilkS")
		)
		(fp_line
			(start 0.67945 -0.305054)
			(end 0.12065 -0.305054)
			(stroke
				(width 0.1)
				(type default)
			)
			(layer "B.Fab")
		)
		(fp_line
			(start 0.12065 -0.305054)
			(end 0.12065 -0.2794)
			(stroke
				(width 0.1)
				(type default)
			)
			(layer "B.Fab")
		)
		(fp_line
			(start -0.12065 -0.3048)
			(end -0.67945 -0.3048)
			(stroke
				(width 0.1)
				(type default)
			)
			(layer "B.Fab")
		)
		(fp_line
			(start -0.67945 -0.3048)
			(end -0.67945 0.3048)
			(stroke
				(width 0.1)
				(type default)
			)
			(layer "B.Fab")
		)
		(fp_line
			(start 0.12065 -0.2794)
			(end -0.12065 -0.2794)
			(stroke
				(width 0.1)
				(type default)
			)
			(layer "B.Fab")
		)
		(fp_line
			(start -0.12065 -0.2794)
			(end -0.12065 -0.3048)
			(stroke
				(width 0.1)
				(type default)
			)
			(layer "B.Fab")
		)
		(fp_line
			(start 0.12065 0.2794)
			(end 0.12065 0.3048)
			(stroke
				(width 0.1)
				(type default)
			)
			(layer "B.Fab")
		)
		(fp_line
			(start -0.120396 0.2794)
			(end 0.12065 0.2794)
			(stroke
				(width 0.1)
				(type default)
			)
			(layer "B.Fab")
		)
		(fp_line
			(start 0.67945 0.3048)
			(end 0.67945 -0.305054)
			(stroke
				(width 0.1)
				(type default)
			)
			(layer "B.Fab")
		)
		(fp_line
			(start 0.12065 0.3048)
			(end 0.67945 0.3048)
			(stroke
				(width 0.1)
				(type default)
			)
			(layer "B.Fab")
		)
		(fp_line
			(start -0.120396 0.3048)
			(end -0.120396 0.2794)
			(stroke
				(width 0.1)
				(type default)
			)
			(layer "B.Fab")
		)
		(fp_line
			(start -0.67945 0.3048)
			(end -0.120396 0.3048)
			(stroke
				(width 0.1)
				(type default)
			)
			(layer "B.Fab")
		)
		(pad "1" smd circle
			(at 0.40005 0 270)
			(size 0 0)
			(layers "B.Cu" "B.Mask" "B.Paste")
			(net "PVDDCR_CPU0_P0_VOS5")
		)
		(pad "2" smd circle
			(at -0.40005 0 270)
			(size 0 0)
			(layers "B.Cu" "B.Mask" "B.Paste")
			(net "PVDDCR_CPU0_P0")
		)
	)
)
